(kicad_pcb
	(version 20260206)
	(generator "pcbnew")
	(generator_version "10.0")
	(general
		(thickness 1.6)
		(legacy_teardrops no)
	)
	(paper "A4")
	(title_block
		(title "peb — Lightning_PEB_BRD.brd")
		(comment 1 "Lightning (Wiwynn / Facebook NVMe JBOF) / footprints 1258-1264 of 2563")
	)
	(layers
		(0 "F.Cu" signal "TOP")
		(4 "In1.Cu" signal "L2GND")
		(6 "In2.Cu" signal "L3")
		(8 "In3.Cu" signal "L4VCC")
		(10 "In4.Cu" signal "L5VCC")
		(12 "In5.Cu" signal "L6")
		(14 "In6.Cu" signal "L7GND")
		(2 "B.Cu" signal "BOTTOM")
		(9 "F.Adhes" user "F.Adhesive")
		(11 "B.Adhes" user "B.Adhesive")
		(13 "F.Paste" user "Package Geometry/Pastemask Top")
		(15 "B.Paste" user "Package Geometry/Pastemask Bottom")
		(5 "F.SilkS" user "Ref Des/Silkscreen Top")
		(7 "B.SilkS" user "Ref Des/Silkscreen Bottom")
		(1 "F.Mask" user "Board Geometry/Soldermask Top")
		(3 "B.Mask" user "Board Geometry/Soldermask Bottom")
		(17 "Dwgs.User" user "User.Drawings")
		(19 "Cmts.User" user "User.Comments")
		(21 "Eco1.User" user "User.Eco1")
		(23 "Eco2.User" user "User.Eco2")
		(25 "Edge.Cuts" user "Board Geometry/Outline")
		(27 "Margin" user)
		(31 "F.CrtYd" user "Package Geometry/Place Bound Top")
		(29 "B.CrtYd" user "Package Geometry/Place Bound Bottom")
		(35 "F.Fab" user "Ref Des/Assembly Top")
		(33 "B.Fab" user "Ref Des/Assembly Bottom")
	)
	(footprint ""
		(layer "F.Cu")
		(at 43.379136 -47.418244 -90)
		(property "Reference" "R410"
			(at 0 0 270)
			(layer "F.SilkS")
			(hide yes)
			(effects
				(font
					(size 1.27 1.27)
				)
			)
		)
		(property "Value" "0R2J-2-GP"
			(at 0.064008 -3.993896 270)
			(unlocked yes)
			(layer "F.Fab")
			(hide yes)
			(effects
				(font
					(size 1.016 1.016)
					(thickness 0.1524)
				)
			)
		)
		(property "Device Type" "R402H16"
			(at 0.064008 -5.517896 270)
			(unlocked yes)
			(layer "F.Fab")
			(hide yes)
			(effects
				(font
					(size 1.016 1.016)
					(thickness 0.1524)
				)
			)
		)
		(duplicate_pad_numbers_are_jumpers no)
		(fp_line
			(start -0.508 -0.9398)
			(end -0.508 0.9398)
			(stroke
				(width 0.1524)
				(type default)
			)
			(layer "F.SilkS")
		)
		(fp_line
			(start 0.508 -0.9398)
			(end -0.508 -0.9398)
			(stroke
				(width 0.1524)
				(type default)
			)
			(layer "F.SilkS")
		)
		(fp_rect
			(start -0.508 0.9398)
			(end 0.508 -0.9398)
			(stroke
				(width 0)
				(type default)
			)
			(fill no)
			(layer "F.CrtYd")
		)
		(fp_rect
			(start -0.508 0.9398)
			(end 0.508 -0.9398)
			(stroke
				(width 0)
				(type default)
			)
			(fill no)
			(layer "F.Fab")
		)
		(pad "1" smd custom
			(at 0 -0.4445 270)
			(size 0.1397 0.1397)
			(layers "F.Cu" "F.Mask" "F.Paste")
			(net "USB_DN_R")
			(options
				(clearance outline)
				(anchor circle)
			)
			(primitives
				(gr_poly
					(pts
						(arc
							(start -0.1778 -0.2794)
							(mid -0.249642 -0.249642)
							(end -0.2794 -0.1778)
						)
						(arc
							(start -0.2794 0.1778)
							(mid -0.249642 0.249642)
							(end -0.1778 0.2794)
						)
						(arc
							(start 0.1778 0.2794)
							(mid 0.249642 0.249642)
							(end 0.2794 0.1778)
						)
						(arc
							(start 0.2794 -0.1778)
							(mid 0.249642 -0.249642)
							(end 0.1778 -0.2794)
						)
					)
					(width 0)
					(fill yes)
				)
			)
		)
		(pad "2" smd custom
			(at 0 0.4445 270)
			(size 0.1397 0.1397)
			(layers "F.Cu" "F.Mask" "F.Paste")
			(net "USB_P1_F_DN1")
			(options
				(clearance outline)
				(anchor circle)
			)
			(primitives
				(gr_poly
					(pts
						(arc
							(start -0.1778 -0.2794)
							(mid -0.249642 -0.249642)
							(end -0.2794 -0.1778)
						)
						(arc
							(start -0.2794 0.1778)
							(mid -0.249642 0.249642)
							(end -0.1778 0.2794)
						)
						(arc
							(start 0.1778 0.2794)
							(mid 0.249642 0.249642)
							(end 0.2794 0.1778)
						)
						(arc
							(start 0.2794 -0.1778)
							(mid 0.249642 -0.249642)
							(end 0.1778 -0.2794)
						)
					)
					(width 0)
					(fill yes)
				)
			)
		)
	)
	(footprint ""
		(layer "F.Cu")
		(at 334.5942 -76.1746 180)
		(property "Reference" "R80"
			(at 0 0 180)
			(layer "F.SilkS")
			(hide yes)
			(effects
				(font
					(size 1.27 1.27)
				)
			)
		)
		(property "Value" "0R2J-2-GP"
			(at 0.064008 -3.993896 180)
			(unlocked yes)
			(layer "F.Fab")
			(hide yes)
			(effects
				(font
					(size 1.016 1.016)
					(thickness 0.1524)
				)
			)
		)
		(property "Device Type" "R402H16"
			(at 0.064008 -5.517896 180)
			(unlocked yes)
			(layer "F.Fab")
			(hide yes)
			(effects
				(font
					(size 1.016 1.016)
					(thickness 0.1524)
				)
			)
		)
		(duplicate_pad_numbers_are_jumpers no)
		(fp_line
			(start 0.508 -0.9398)
			(end -0.508 -0.9398)
			(stroke
				(width 0.1524)
				(type default)
			)
			(layer "F.SilkS")
		)
		(fp_line
			(start -0.508 -0.9398)
			(end -0.508 0.9398)
			(stroke
				(width 0.1524)
				(type default)
			)
			(layer "F.SilkS")
		)
		(fp_rect
			(start -0.508 0.9398)
			(end 0.508 -0.9398)
			(stroke
				(width 0)
				(type default)
			)
			(fill no)
			(layer "F.CrtYd")
		)
		(fp_rect
			(start -0.508 0.9398)
			(end 0.508 -0.9398)
			(stroke
				(width 0)
				(type default)
			)
			(fill no)
			(layer "F.Fab")
		)
		(pad "1" smd custom
			(at 0 -0.4445 180)
			(size 0.1397 0.1397)
			(layers "F.Cu" "F.Mask" "F.Paste")
			(net "P0V9_E_VFB_R")
			(options
				(clearance outline)
				(anchor circle)
			)
			(primitives
				(gr_poly
					(pts
						(arc
							(start -0.1778 -0.2794)
							(mid -0.249642 -0.249642)
							(end -0.2794 -0.1778)
						)
						(arc
							(start -0.2794 0.1778)
							(mid -0.249642 0.249642)
							(end -0.1778 0.2794)
						)
						(arc
							(start 0.1778 0.2794)
							(mid 0.249642 0.249642)
							(end 0.2794 0.1778)
						)
						(arc
							(start 0.2794 -0.1778)
							(mid 0.249642 -0.249642)
							(end 0.1778 -0.2794)
						)
					)
					(width 0)
					(fill yes)
				)
			)
		)
		(pad "2" smd custom
			(at 0 0.4445 180)
			(size 0.1397 0.1397)
			(layers "F.Cu" "F.Mask" "F.Paste")
			(net "DUT_VDD")
			(options
				(clearance outline)
				(anchor circle)
			)
			(primitives
				(gr_poly
					(pts
						(arc
							(start -0.1778 -0.2794)
							(mid -0.249642 -0.249642)
							(end -0.2794 -0.1778)
						)
						(arc
							(start -0.2794 0.1778)
							(mid -0.249642 0.249642)
							(end -0.1778 0.2794)
						)
						(arc
							(start 0.1778 0.2794)
							(mid 0.249642 0.249642)
							(end 0.2794 0.1778)
						)
						(arc
							(start 0.2794 -0.1778)
							(mid 0.249642 -0.249642)
							(end 0.1778 -0.2794)
						)
					)
					(width 0)
					(fill yes)
				)
			)
		)
	)
	(footprint ""
		(layer "F.Cu")
		(at 197.2564 -18.796 -90)
		(property "Reference" "R703"
			(at 0 0 270)
			(layer "F.SilkS")
			(hide yes)
			(effects
				(font
					(size 1.27 1.27)
				)
			)
		)
		(property "Value" "4K7R2F-GP"
			(at 0.064008 -3.993896 270)
			(unlocked yes)
			(layer "F.Fab")
			(hide yes)
			(effects
				(font
					(size 1.016 1.016)
					(thickness 0.1524)
				)
			)
		)
		(property "Device Type" "R402H16"
			(at 0.064008 -5.517896 270)
			(unlocked yes)
			(layer "F.Fab")
			(hide yes)
			(effects
				(font
					(size 1.016 1.016)
					(thickness 0.1524)
				)
			)
		)
		(duplicate_pad_numbers_are_jumpers no)
		(fp_line
			(start -0.508 -0.9398)
			(end -0.508 0.9398)
			(stroke
				(width 0.1524)
				(type default)
			)
			(layer "F.SilkS")
		)
		(fp_line
			(start 0.508 -0.9398)
			(end -0.508 -0.9398)
			(stroke
				(width 0.1524)
				(type default)
			)
			(layer "F.SilkS")
		)
		(fp_rect
			(start -0.508 0.9398)
			(end 0.508 -0.9398)
			(stroke
				(width 0)
				(type default)
			)
			(fill no)
			(layer "F.CrtYd")
		)
		(fp_rect
			(start -0.508 0.9398)
			(end 0.508 -0.9398)
			(stroke
				(width 0)
				(type default)
			)
			(fill no)
			(layer "F.Fab")
		)
		(pad "1" smd custom
			(at 0 -0.4445 270)
			(size 0.1397 0.1397)
			(layers "F.Cu" "F.Mask" "F.Paste")
			(net "MINISAS_CN16_A_I2C_INT#")
			(options
				(clearance outline)
				(anchor circle)
			)
			(primitives
				(gr_poly
					(pts
						(arc
							(start -0.1778 -0.2794)
							(mid -0.249642 -0.249642)
							(end -0.2794 -0.1778)
						)
						(arc
							(start -0.2794 0.1778)
							(mid -0.249642 0.249642)
							(end -0.1778 0.2794)
						)
						(arc
							(start 0.1778 0.2794)
							(mid 0.249642 0.249642)
							(end 0.2794 0.1778)
						)
						(arc
							(start 0.2794 -0.1778)
							(mid 0.249642 -0.249642)
							(end 0.1778 -0.2794)
						)
					)
					(width 0)
					(fill yes)
				)
			)
		)
		(pad "2" smd custom
			(at 0 0.4445 270)
			(size 0.1397 0.1397)
			(layers "F.Cu" "F.Mask" "F.Paste")
			(net "P3V3_STBY")
			(options
				(clearance outline)
				(anchor circle)
			)
			(primitives
				(gr_poly
					(pts
						(arc
							(start -0.1778 -0.2794)
							(mid -0.249642 -0.249642)
							(end -0.2794 -0.1778)
						)
						(arc
							(start -0.2794 0.1778)
							(mid -0.249642 0.249642)
							(end -0.1778 0.2794)
						)
						(arc
							(start 0.1778 0.2794)
							(mid 0.249642 0.249642)
							(end 0.2794 0.1778)
						)
						(arc
							(start 0.2794 -0.1778)
							(mid 0.249642 -0.249642)
							(end 0.1778 -0.2794)
						)
					)
					(width 0)
					(fill yes)
				)
			)
		)
	)
	(footprint ""
		(layer "F.Cu")
		(at 20.864576 -128.227074 90)
		(property "Reference" "R368"
			(at 0 0 90)
			(layer "F.SilkS")
			(hide yes)
			(effects
				(font
					(size 1.27 1.27)
				)
			)
		)
		(property "Value" "3K3R2F-2-GP"
			(at 0.064008 -3.993896 90)
			(unlocked yes)
			(layer "F.Fab")
			(hide yes)
			(effects
				(font
					(size 1.016 1.016)
					(thickness 0.1524)
				)
			)
		)
		(property "Device Type" "R402H16"
			(at 0.064008 -5.517896 90)
			(unlocked yes)
			(layer "F.Fab")
			(hide yes)
			(effects
				(font
					(size 1.016 1.016)
					(thickness 0.1524)
				)
			)
		)
		(duplicate_pad_numbers_are_jumpers no)
		(fp_line
			(start 0.508 -0.9398)
			(end -0.508 -0.9398)
			(stroke
				(width 0.1524)
				(type default)
			)
			(layer "F.SilkS")
		)
		(fp_line
			(start -0.508 -0.9398)
			(end -0.508 0.9398)
			(stroke
				(width 0.1524)
				(type default)
			)
			(layer "F.SilkS")
		)
		(fp_rect
			(start -0.508 0.9398)
			(end 0.508 -0.9398)
			(stroke
				(width 0)
				(type default)
			)
			(fill no)
			(layer "F.CrtYd")
		)
		(fp_rect
			(start -0.508 0.9398)
			(end 0.508 -0.9398)
			(stroke
				(width 0)
				(type default)
			)
			(fill no)
			(layer "F.Fab")
		)
		(pad "1" smd custom
			(at 0 -0.4445 90)
			(size 0.1397 0.1397)
			(layers "F.Cu" "F.Mask" "F.Paste")
			(net "P3V3_STBY")
			(options
				(clearance outline)
				(anchor circle)
			)
			(primitives
				(gr_poly
					(pts
						(arc
							(start -0.1778 -0.2794)
							(mid -0.249642 -0.249642)
							(end -0.2794 -0.1778)
						)
						(arc
							(start -0.2794 0.1778)
							(mid -0.249642 0.249642)
							(end -0.1778 0.2794)
						)
						(arc
							(start 0.1778 0.2794)
							(mid 0.249642 0.249642)
							(end 0.2794 0.1778)
						)
						(arc
							(start 0.2794 -0.1778)
							(mid 0.249642 -0.249642)
							(end 0.1778 -0.2794)
						)
					)
					(width 0)
					(fill yes)
				)
			)
		)
		(pad "2" smd custom
			(at 0 0.4445 90)
			(size 0.1397 0.1397)
			(layers "F.Cu" "F.Mask" "F.Paste")
			(net "ROMA15")
			(options
				(clearance outline)
				(anchor circle)
			)
			(primitives
				(gr_poly
					(pts
						(arc
							(start -0.1778 -0.2794)
							(mid -0.249642 -0.249642)
							(end -0.2794 -0.1778)
						)
						(arc
							(start -0.2794 0.1778)
							(mid -0.249642 0.249642)
							(end -0.1778 0.2794)
						)
						(arc
							(start 0.1778 0.2794)
							(mid 0.249642 0.249642)
							(end 0.2794 0.1778)
						)
						(arc
							(start 0.2794 -0.1778)
							(mid 0.249642 -0.249642)
							(end 0.1778 -0.2794)
						)
					)
					(width 0)
					(fill yes)
				)
			)
		)
	)
	(footprint ""
		(layer "F.Cu")
		(at 339.884512 -184.878218 180)
		(property "Reference" "R7930"
			(at 0 0 180)
			(layer "F.SilkS")
			(hide yes)
			(effects
				(font
					(size 1.27 1.27)
				)
			)
		)
		(property "Value" "0R2J-2-GP"
			(at 0.064008 -3.993896 180)
			(unlocked yes)
			(layer "F.Fab")
			(hide yes)
			(effects
				(font
					(size 1.016 1.016)
					(thickness 0.1524)
				)
			)
		)
		(property "Device Type" "R402H16"
			(at 0.064008 -5.517896 180)
			(unlocked yes)
			(layer "F.Fab")
			(hide yes)
			(effects
				(font
					(size 1.016 1.016)
					(thickness 0.1524)
				)
			)
		)
		(duplicate_pad_numbers_are_jumpers no)
		(fp_line
			(start 0.508 -0.9398)
			(end -0.508 -0.9398)
			(stroke
				(width 0.1524)
				(type default)
			)
			(layer "F.SilkS")
		)
		(fp_line
			(start -0.508 -0.9398)
			(end -0.508 0.9398)
			(stroke
				(width 0.1524)
				(type default)
			)
			(layer "F.SilkS")
		)
		(fp_rect
			(start -0.508 0.9398)
			(end 0.508 -0.9398)
			(stroke
				(width 0)
				(type default)
			)
			(fill no)
			(layer "F.CrtYd")
		)
		(fp_rect
			(start -0.508 0.9398)
			(end 0.508 -0.9398)
			(stroke
				(width 0)
				(type default)
			)
			(fill no)
			(layer "F.Fab")
		)
		(pad "1" smd custom
			(at 0 -0.4445 180)
			(size 0.1397 0.1397)
			(layers "F.Cu" "F.Mask" "F.Paste")
			(net "SSD_PRSNT#14")
			(options
				(clearance outline)
				(anchor circle)
			)
			(primitives
				(gr_poly
					(pts
						(arc
							(start -0.1778 -0.2794)
							(mid -0.249642 -0.249642)
							(end -0.2794 -0.1778)
						)
						(arc
							(start -0.2794 0.1778)
							(mid -0.249642 0.249642)
							(end -0.1778 0.2794)
						)
						(arc
							(start 0.1778 0.2794)
							(mid 0.249642 0.249642)
							(end 0.2794 0.1778)
						)
						(arc
							(start 0.2794 -0.1778)
							(mid 0.249642 -0.249642)
							(end 0.1778 -0.2794)
						)
					)
					(width 0)
					(fill yes)
				)
			)
		)
		(pad "2" smd custom
			(at 0 0.4445 180)
			(size 0.1397 0.1397)
			(layers "F.Cu" "F.Mask" "F.Paste")
			(net "SSD_PRSNT#14_R")
			(options
				(clearance outline)
				(anchor circle)
			)
			(primitives
				(gr_poly
					(pts
						(arc
							(start -0.1778 -0.2794)
							(mid -0.249642 -0.249642)
							(end -0.2794 -0.1778)
						)
						(arc
							(start -0.2794 0.1778)
							(mid -0.249642 0.249642)
							(end -0.1778 0.2794)
						)
						(arc
							(start 0.1778 0.2794)
							(mid 0.249642 0.249642)
							(end 0.2794 0.1778)
						)
						(arc
							(start 0.2794 -0.1778)
							(mid 0.249642 -0.249642)
							(end 0.1778 -0.2794)
						)
					)
					(width 0)
					(fill yes)
				)
			)
		)
	)
	(footprint ""
		(layer "F.Cu")
		(at 119.806974 -78.285848)
		(property "Reference" "R5202"
			(at 0 0 0)
			(layer "F.SilkS")
			(hide yes)
			(effects
				(font
					(size 1.27 1.27)
				)
			)
		)
		(property "Value" "1KR2J-1-GP"
			(at 0.064008 -3.993896 0)
			(unlocked yes)
			(layer "F.Fab")
			(hide yes)
			(effects
				(font
					(size 1.016 1.016)
					(thickness 0.1524)
				)
			)
		)
		(property "Device Type" "R402H16"
			(at 0.064008 -5.517896 0)
			(unlocked yes)
			(layer "F.Fab")
			(hide yes)
			(effects
				(font
					(size 1.016 1.016)
					(thickness 0.1524)
				)
			)
		)
		(duplicate_pad_numbers_are_jumpers no)
		(fp_line
			(start -0.508 -0.9398)
			(end -0.508 0.9398)
			(stroke
				(width 0.1524)
				(type default)
			)
			(layer "F.SilkS")
		)
		(fp_line
			(start 0.508 -0.9398)
			(end -0.508 -0.9398)
			(stroke
				(width 0.1524)
				(type default)
			)
			(layer "F.SilkS")
		)
		(fp_rect
			(start -0.508 0.9398)
			(end 0.508 -0.9398)
			(stroke
				(width 0)
				(type default)
			)
			(fill no)
			(layer "F.CrtYd")
		)
		(fp_rect
			(start -0.508 0.9398)
			(end 0.508 -0.9398)
			(stroke
				(width 0)
				(type default)
			)
			(fill no)
			(layer "F.Fab")
		)
		(pad "1" smd custom
			(at 0 -0.4445)
			(size 0.1397 0.1397)
			(layers "F.Cu" "F.Mask" "F.Paste")
			(net "P3V0_BAT_R")
			(options
				(clearance outline)
				(anchor circle)
			)
			(primitives
				(gr_poly
					(pts
						(arc
							(start -0.1778 -0.2794)
							(mid -0.249642 -0.249642)
							(end -0.2794 -0.1778)
						)
						(arc
							(start -0.2794 0.1778)
							(mid -0.249642 0.249642)
							(end -0.1778 0.2794)
						)
						(arc
							(start 0.1778 0.2794)
							(mid 0.249642 0.249642)
							(end 0.2794 0.1778)
						)
						(arc
							(start 0.2794 -0.1778)
							(mid 0.249642 -0.249642)
							(end 0.1778 -0.2794)
						)
					)
					(width 0)
					(fill yes)
				)
			)
		)
		(pad "2" smd custom
			(at 0 0.4445)
			(size 0.1397 0.1397)
			(layers "F.Cu" "F.Mask" "F.Paste")
			(net "P3V0_BAT")
			(options
				(clearance outline)
				(anchor circle)
			)
			(primitives
				(gr_poly
					(pts
						(arc
							(start -0.1778 -0.2794)
							(mid -0.249642 -0.249642)
							(end -0.2794 -0.1778)
						)
						(arc
							(start -0.2794 0.1778)
							(mid -0.249642 0.249642)
							(end -0.1778 0.2794)
						)
						(arc
							(start 0.1778 0.2794)
							(mid 0.249642 0.249642)
							(end 0.2794 0.1778)
						)
						(arc
							(start 0.2794 -0.1778)
							(mid 0.249642 -0.249642)
							(end 0.1778 -0.2794)
						)
					)
					(width 0)
					(fill yes)
				)
			)
		)
	)
	(footprint ""
		(layer "F.Cu")
		(at 324.485 -101.473 180)
		(property "Reference" "R4178"
			(at 0 0 180)
			(layer "F.SilkS")
			(hide yes)
			(effects
				(font
					(size 1.27 1.27)
				)
			)
		)
		(property "Value" "4K7R2F-GP"
			(at 0.064008 -3.993896 180)
			(unlocked yes)
			(layer "F.Fab")
			(hide yes)
			(effects
				(font
					(size 1.016 1.016)
					(thickness 0.1524)
				)
			)
		)
		(property "Device Type" "R402H16"
			(at 0.064008 -5.517896 180)
			(unlocked yes)
			(layer "F.Fab")
			(hide yes)
			(effects
				(font
					(size 1.016 1.016)
					(thickness 0.1524)
				)
			)
		)
		(duplicate_pad_numbers_are_jumpers no)
		(fp_line
			(start 0.508 -0.9398)
			(end -0.508 -0.9398)
			(stroke
				(width 0.1524)
				(type default)
			)
			(layer "F.SilkS")
		)
		(fp_line
			(start -0.508 -0.9398)
			(end -0.508 0.9398)
			(stroke
				(width 0.1524)
				(type default)
			)
			(layer "F.SilkS")
		)
		(fp_rect
			(start -0.508 0.9398)
			(end 0.508 -0.9398)
			(stroke
				(width 0)
				(type default)
			)
			(fill no)
			(layer "F.CrtYd")
		)
		(fp_rect
			(start -0.508 0.9398)
			(end 0.508 -0.9398)
			(stroke
				(width 0)
				(type default)
			)
			(fill no)
			(layer "F.Fab")
		)
		(pad "1" smd custom
			(at 0 -0.4445 180)
			(size 0.1397 0.1397)
			(layers "F.Cu" "F.Mask" "F.Paste")
			(net "PEWAKE#")
			(options
				(clearance outline)
				(anchor circle)
			)
			(primitives
				(gr_poly
					(pts
						(arc
							(start -0.1778 -0.2794)
							(mid -0.249642 -0.249642)
							(end -0.2794 -0.1778)
						)
						(arc
							(start -0.2794 0.1778)
							(mid -0.249642 0.249642)
							(end -0.1778 0.2794)
						)
						(arc
							(start 0.1778 0.2794)
							(mid 0.249642 0.249642)
							(end 0.2794 0.1778)
						)
						(arc
							(start 0.2794 -0.1778)
							(mid 0.249642 -0.249642)
							(end 0.1778 -0.2794)
						)
					)
					(width 0)
					(fill yes)
				)
			)
		)
		(pad "2" smd custom
			(at 0 0.4445 180)
			(size 0.1397 0.1397)
			(layers "F.Cu" "F.Mask" "F.Paste")
			(net "P3V3_STBY")
			(options
				(clearance outline)
				(anchor circle)
			)
			(primitives
				(gr_poly
					(pts
						(arc
							(start -0.1778 -0.2794)
							(mid -0.249642 -0.249642)
							(end -0.2794 -0.1778)
						)
						(arc
							(start -0.2794 0.1778)
							(mid -0.249642 0.249642)
							(end -0.1778 0.2794)
						)
						(arc
							(start 0.1778 0.2794)
							(mid 0.249642 0.249642)
							(end 0.2794 0.1778)
						)
						(arc
							(start 0.2794 -0.1778)
							(mid 0.249642 -0.249642)
							(end 0.1778 -0.2794)
						)
					)
					(width 0)
					(fill yes)
				)
			)
		)
	)
)
